(kicad_pcb
	(version 20211014)
	(generator pcbnew)
	(general
    (thickness 1.6)
  )
	(paper "A4")
	(title_block
    (title "SA800U (Snapdragon 845) Baseboard")
    (date "2023-10-19")
    (rev "1.0.3")
    (company "Antmicro Ltd.")
    (comment 1 "www.antmicro.com")
		(comment 9 "footprints 382-391 of 589")
	)
	(layers
    (0 "F.Cu" signal)
    (1 "In1.Cu" power)
    (2 "In2.Cu" signal)
    (3 "In3.Cu" signal)
    (4 "In4.Cu" power)
    (31 "B.Cu" signal)
    (32 "B.Adhes" user "B.Adhesive")
    (33 "F.Adhes" user "F.Adhesive")
    (34 "B.Paste" user)
    (35 "F.Paste" user)
    (36 "B.SilkS" user "B.Silkscreen")
    (37 "F.SilkS" user "F.Silkscreen")
    (38 "B.Mask" user)
    (39 "F.Mask" user)
    (40 "Dwgs.User" user "User.Drawings")
    (41 "Cmts.User" user "User.Comments")
    (42 "Eco1.User" user "User.Eco1")
    (43 "Eco2.User" user "User.Eco2")
    (44 "Edge.Cuts" user)
    (45 "Margin" user)
    (46 "B.CrtYd" user "B.Courtyard")
    (47 "F.CrtYd" user "F.Courtyard")
    (48 "B.Fab" user)
    (49 "F.Fab" user)
  )
	(footprint "sa800u-baseboard-hw-footprints:C_0402_1005Metric" (layer "B.Cu")
    (tedit 616D63CF)
    (at 118.25 138.95 -90)
    (descr "Capacitor SMD 0402")
    (tags "capacitor SMD 0402")
    (property "Author" "Antmicro")
    (property "Dielectric" "X5R")
    (property "License" "Apache-2.0")
    (property "MPN" "GRM155R61H104KE14D")
    (property "Manufacturer" "Murata")
    (property "Sheetfile" "usb-c-interface.kicad_sch")
    (property "Sheetname" "USB-C Interface ")
    (property "Val" "100n")
    (property "Voltage" "50V")
    (attr smd)
    (fp_text reference "C91" (at -3.05 -0.34 90) (layer "B.SilkS")
      (effects (font (size 0.7 0.7) (thickness 0.15)) (justify left bottom mirror))
    )
    (fp_text value "C_100n_0402" (at 0 -1.4 90) (layer "B.Fab")
      (effects (font (size 0.7 0.7) (thickness 0.15)) (justify left bottom mirror))
    )
    (fp_text user "Author: Antmicro" (at -0.932 -4.17 90) (layer "B.Fab") hide
      (effects (font (size 0.7 0.7) (thickness 0.15)) (justify left bottom mirror))
    )
    (fp_text user "License: Apache-2.0" (at -0.932 -5.17 90) (layer "B.Fab") hide
      (effects (font (size 0.7 0.7) (thickness 0.15)) (justify left bottom mirror))
    )
    (fp_text user "${REFERENCE}" (at -0.932 -3.168 90) (layer "B.Fab") hide
      (effects (font (size 0.7 0.7) (thickness 0.15)) (justify left bottom mirror))
    )
    (fp_rect (start -0.94 0.47) (end 0.94 -0.47) (layer "B.CrtYd") (width 0.05) (fill none))
    (fp_rect (start -0.499 0.249) (end 0.499 -0.249) (layer "B.Fab") (width 0.15) (fill none))
    (pad "1" smd roundrect (at -0.484 0 270) (size 0.59 0.64) (layers "B.Cu" "B.Paste" "B.Mask") (roundrect_rratio 0.25)
      (net 221 "/USB-C Interface /USB2C_TX2_P") (pintype "passive"))
    (pad "2" smd roundrect (at 0.484 0 270) (size 0.59 0.64) (layers "B.Cu" "B.Paste" "B.Mask") (roundrect_rratio 0.25)
      (net 222 "/USB-C Interface /USB2C_TX2_C_P") (pintype "passive"))
  )
	(footprint "sa800u-baseboard-hw-footprints:C_0402_1005Metric" (layer "B.Cu")
    (tedit 616D63CF)
    (at 112.25 138.95 -90)
    (descr "Capacitor SMD 0402")
    (tags "capacitor SMD 0402")
    (property "Author" "Antmicro")
    (property "Dielectric" "X5R")
    (property "License" "Apache-2.0")
    (property "MPN" "GRM155R61H104KE14D")
    (property "Manufacturer" "Murata")
    (property "Sheetfile" "usb-c-interface.kicad_sch")
    (property "Sheetname" "USB-C Interface ")
    (property "Val" "100n")
    (property "Voltage" "50V")
    (attr smd)
    (fp_text reference "C94" (at -3.06 -0.43 90) (layer "B.SilkS")
      (effects (font (size 0.7 0.7) (thickness 0.15)) (justify left bottom mirror))
    )
    (fp_text value "C_100n_0402" (at 0 -1.4 90) (layer "B.Fab")
      (effects (font (size 0.7 0.7) (thickness 0.15)) (justify left bottom mirror))
    )
    (fp_text user "License: Apache-2.0" (at -0.932 -5.17 90) (layer "B.Fab") hide
      (effects (font (size 0.7 0.7) (thickness 0.15)) (justify left bottom mirror))
    )
    (fp_text user "${REFERENCE}" (at -0.932 -3.168 90) (layer "B.Fab") hide
      (effects (font (size 0.7 0.7) (thickness 0.15)) (justify left bottom mirror))
    )
    (fp_text user "Author: Antmicro" (at -0.932 -4.17 90) (layer "B.Fab") hide
      (effects (font (size 0.7 0.7) (thickness 0.15)) (justify left bottom mirror))
    )
    (fp_rect (start -0.94 0.47) (end 0.94 -0.47) (layer "B.CrtYd") (width 0.05) (fill none))
    (fp_rect (start -0.499 0.249) (end 0.499 -0.249) (layer "B.Fab") (width 0.15) (fill none))
    (pad "1" smd roundrect (at -0.484 0 270) (size 0.59 0.64) (layers "B.Cu" "B.Paste" "B.Mask") (roundrect_rratio 0.25)
      (net 223 "/USB-C Interface /USB2C_RX1_P") (pintype "passive"))
    (pad "2" smd roundrect (at 0.484 0 270) (size 0.59 0.64) (layers "B.Cu" "B.Paste" "B.Mask") (roundrect_rratio 0.25)
      (net 224 "/USB-C Interface /USB2C_RX1_C_P") (pintype "passive"))
  )
	(footprint "sa800u-baseboard-hw-footprints:C_0402_1005Metric" (layer "B.Cu")
    (tedit 616D63CF)
    (at 119.25 138.95 -90)
    (descr "Capacitor SMD 0402")
    (tags "capacitor SMD 0402")
    (property "Author" "Antmicro")
    (property "Dielectric" "X5R")
    (property "License" "Apache-2.0")
    (property "MPN" "GRM155R61H104KE14D")
    (property "Manufacturer" "Murata")
    (property "Sheetfile" "usb-c-interface.kicad_sch")
    (property "Sheetname" "USB-C Interface ")
    (property "Val" "100n")
    (property "Voltage" "50V")
    (attr smd)
    (fp_text reference "C95" (at -3.05 -0.34 90) (layer "B.SilkS")
      (effects (font (size 0.7 0.7) (thickness 0.15)) (justify left bottom mirror))
    )
    (fp_text value "C_100n_0402" (at 0 -1.4 90) (layer "B.Fab")
      (effects (font (size 0.7 0.7) (thickness 0.15)) (justify left bottom mirror))
    )
    (fp_text user "${REFERENCE}" (at -0.932 -3.168 90) (layer "B.Fab") hide
      (effects (font (size 0.7 0.7) (thickness 0.15)) (justify left bottom mirror))
    )
    (fp_text user "Author: Antmicro" (at -0.932 -4.17 90) (layer "B.Fab") hide
      (effects (font (size 0.7 0.7) (thickness 0.15)) (justify left bottom mirror))
    )
    (fp_text user "License: Apache-2.0" (at -0.932 -5.17 90) (layer "B.Fab") hide
      (effects (font (size 0.7 0.7) (thickness 0.15)) (justify left bottom mirror))
    )
    (fp_rect (start -0.94 0.47) (end 0.94 -0.47) (layer "B.CrtYd") (width 0.05) (fill none))
    (fp_rect (start -0.499 0.249) (end 0.499 -0.249) (layer "B.Fab") (width 0.15) (fill none))
    (pad "1" smd roundrect (at -0.484 0 270) (size 0.59 0.64) (layers "B.Cu" "B.Paste" "B.Mask") (roundrect_rratio 0.25)
      (net 225 "/USB-C Interface /USB2C_TX2_N") (pintype "passive"))
    (pad "2" smd roundrect (at 0.484 0 270) (size 0.59 0.64) (layers "B.Cu" "B.Paste" "B.Mask") (roundrect_rratio 0.25)
      (net 226 "/USB-C Interface /USB2C_TX2_C_N") (pintype "passive"))
  )
	(footprint "sa800u-baseboard-hw-footprints:C_0402_1005Metric" (layer "B.Cu")
    (tedit 616D63CF)
    (at 115.8 130.4 180)
    (descr "Capacitor SMD 0402")
    (tags "capacitor SMD 0402")
    (property "Author" "Antmicro")
    (property "Dielectric" "X5R")
    (property "License" "Apache-2.0")
    (property "MPN" "GRM155R61H104KE14D")
    (property "Manufacturer" "Murata")
    (property "Sheetfile" "usb-c-interface.kicad_sch")
    (property "Sheetname" "USB-C Interface ")
    (property "Val" "100n")
    (property "Voltage" "50V")
    (attr smd)
    (fp_text reference "C72" (at -1.05 0.68) (layer "B.SilkS")
      (effects (font (size 0.7 0.7) (thickness 0.15)) (justify left bottom mirror))
    )
    (fp_text value "C_100n_0402" (at 0 -1.4) (layer "B.Fab")
      (effects (font (size 0.7 0.7) (thickness 0.15)) (justify left bottom mirror))
    )
    (fp_text user "License: Apache-2.0" (at -0.932 -5.17) (layer "B.Fab") hide
      (effects (font (size 0.7 0.7) (thickness 0.15)) (justify left bottom mirror))
    )
    (fp_text user "${REFERENCE}" (at -0.932 -3.168) (layer "B.Fab") hide
      (effects (font (size 0.7 0.7) (thickness 0.15)) (justify left bottom mirror))
    )
    (fp_text user "Author: Antmicro" (at -0.932 -4.17) (layer "B.Fab") hide
      (effects (font (size 0.7 0.7) (thickness 0.15)) (justify left bottom mirror))
    )
    (fp_rect (start -0.94 0.47) (end 0.94 -0.47) (layer "B.CrtYd") (width 0.05) (fill none))
    (fp_rect (start -0.499 0.249) (end 0.499 -0.249) (layer "B.Fab") (width 0.15) (fill none))
    (pad "1" smd roundrect (at -0.484 0 180) (size 0.59 0.64) (layers "B.Cu" "B.Paste" "B.Mask") (roundrect_rratio 0.25)
      (net 131 "3V3_SYS") (pintype "passive"))
    (pad "2" smd roundrect (at 0.484 0 180) (size 0.59 0.64) (layers "B.Cu" "B.Paste" "B.Mask") (roundrect_rratio 0.25)
      (net 1 "GND") (pintype "passive"))
  )
	(footprint "sa800u-baseboard-hw-footprints:C_0402_1005Metric" (layer "B.Cu")
    (tedit 616D63CF)
    (at 119.6 133.5 -90)
    (descr "Capacitor SMD 0402")
    (tags "capacitor SMD 0402")
    (property "Author" "Antmicro")
    (property "Dielectric" "X5R")
    (property "License" "Apache-2.0")
    (property "MPN" "GRM155R61H104KE14D")
    (property "Manufacturer" "Murata")
    (property "Sheetfile" "usb-c-interface.kicad_sch")
    (property "Sheetname" "USB-C Interface ")
    (property "Val" "100n")
    (property "Voltage" "50V")
    (attr smd)
    (fp_text reference "C73" (at -1.09 -2.34 90) (layer "B.SilkS")
      (effects (font (size 0.7 0.7) (thickness 0.15)) (justify left bottom mirror))
    )
    (fp_text value "C_100n_0402" (at 0 -1.4 90) (layer "B.Fab")
      (effects (font (size 0.7 0.7) (thickness 0.15)) (justify left bottom mirror))
    )
    (fp_text user "Author: Antmicro" (at -0.932 -4.17 90) (layer "B.Fab") hide
      (effects (font (size 0.7 0.7) (thickness 0.15)) (justify left bottom mirror))
    )
    (fp_text user "${REFERENCE}" (at -0.932 -3.168 90) (layer "B.Fab") hide
      (effects (font (size 0.7 0.7) (thickness 0.15)) (justify left bottom mirror))
    )
    (fp_text user "License: Apache-2.0" (at -0.932 -5.17 90) (layer "B.Fab") hide
      (effects (font (size 0.7 0.7) (thickness 0.15)) (justify left bottom mirror))
    )
    (fp_rect (start -0.94 0.47) (end 0.94 -0.47) (layer "B.CrtYd") (width 0.05) (fill none))
    (fp_rect (start -0.499 0.249) (end 0.499 -0.249) (layer "B.Fab") (width 0.15) (fill none))
    (pad "1" smd roundrect (at -0.484 0 270) (size 0.59 0.64) (layers "B.Cu" "B.Paste" "B.Mask") (roundrect_rratio 0.25)
      (net 131 "3V3_SYS") (pintype "passive"))
    (pad "2" smd roundrect (at 0.484 0 270) (size 0.59 0.64) (layers "B.Cu" "B.Paste" "B.Mask") (roundrect_rratio 0.25)
      (net 1 "GND") (pintype "passive"))
  )
	(footprint "sa800u-baseboard-hw-footprints:C_0603_1608Metric" (layer "B.Cu")
    (tedit 5D5E94D2)
    (at 103.5 149.25 -90)
    (descr "Capacitor SMD 0603")
    (tags "capacitor 0603")
    (property "Author" "Antmicro")
    (property "Dielectric" "")
    (property "License" "Apache-2.0")
    (property "MPN" "GRM188R60J476ME15D")
    (property "Manufacturer" "Murata")
    (property "Sheetfile" "usb-c-interface.kicad_sch")
    (property "Sheetname" "USB-C Interface ")
    (property "Val" "47u")
    (property "Voltage" "")
    (attr smd)
    (fp_text reference "C89" (at -1.12 0.8 90) (layer "B.SilkS")
      (effects (font (size 0.7 0.7) (thickness 0.15)) (justify left bottom mirror))
    )
    (fp_text value "C_47u_0603" (at 0 -1.6 90) (layer "B.Fab")
      (effects (font (size 0.7 0.7) (thickness 0.15)) (justify left bottom mirror))
    )
    (fp_text user "Author: Antmicro" (at -1.682 -4.894 90) (layer "B.Fab") hide
      (effects (font (size 0.7 0.7) (thickness 0.15)) (justify left bottom mirror))
    )
    (fp_text user "${REFERENCE}" (at -1.682 -3.895 90) (layer "B.Fab") hide
      (effects (font (size 0.7 0.7) (thickness 0.15)) (justify left bottom mirror))
    )
    (fp_text user "License: Apache-2.0" (at -1.682 -5.895 90) (layer "B.Fab") hide
      (effects (font (size 0.7 0.7) (thickness 0.15)) (justify left bottom mirror))
    )
    (fp_line (start -0.3 0.3) (end 0.3 0.3) (layer "B.SilkS") (width 0.15))
    (fp_line (start -0.3 -0.3) (end 0.3 -0.3) (layer "B.SilkS") (width 0.15))
    (fp_rect (start -1.24 0.7) (end 1.24 -0.7) (layer "B.CrtYd") (width 0.05) (fill none))
    (fp_rect (start -0.8 0.4) (end 0.8 -0.4) (layer "B.Fab") (width 0.15) (fill none))
    (pad "1" smd roundrect (at -0.7 0 270) (size 0.6 0.8) (layers "B.Cu" "B.Paste" "B.Mask") (roundrect_rratio 0.2)
      (net 66 "USB_VBUS") (pintype "passive"))
    (pad "2" smd roundrect (at 0.7 0 270) (size 0.6 0.8) (layers "B.Cu" "B.Paste" "B.Mask") (roundrect_rratio 0.2)
      (net 1 "GND") (pintype "passive"))
  )
	(footprint "sa800u-baseboard-hw-footprints:C_0603_1608Metric" (layer "B.Cu")
    (tedit 5D5E94D2)
    (at 99.5 149.25 -90)
    (descr "Capacitor SMD 0603")
    (tags "capacitor 0603")
    (property "Author" "Antmicro")
    (property "Dielectric" "")
    (property "License" "Apache-2.0")
    (property "MPN" "GRM188R60J476ME15D")
    (property "Manufacturer" "Murata")
    (property "Sheetfile" "usb-c-interface.kicad_sch")
    (property "Sheetname" "USB-C Interface ")
    (property "Val" "47u")
    (property "Voltage" "")
    (attr smd)
    (fp_text reference "C96" (at -1.12 0.8 90) (layer "B.SilkS")
      (effects (font (size 0.7 0.7) (thickness 0.15)) (justify left bottom mirror))
    )
    (fp_text value "C_47u_0603" (at 0 -1.6 90) (layer "B.Fab")
      (effects (font (size 0.7 0.7) (thickness 0.15)) (justify left bottom mirror))
    )
    (fp_text user "License: Apache-2.0" (at -1.682 -5.895 90) (layer "B.Fab") hide
      (effects (font (size 0.7 0.7) (thickness 0.15)) (justify left bottom mirror))
    )
    (fp_text user "${REFERENCE}" (at -1.682 -3.895 90) (layer "B.Fab") hide
      (effects (font (size 0.7 0.7) (thickness 0.15)) (justify left bottom mirror))
    )
    (fp_text user "Author: Antmicro" (at -1.682 -4.894 90) (layer "B.Fab") hide
      (effects (font (size 0.7 0.7) (thickness 0.15)) (justify left bottom mirror))
    )
    (fp_line (start -0.3 -0.3) (end 0.3 -0.3) (layer "B.SilkS") (width 0.15))
    (fp_line (start -0.3 0.3) (end 0.3 0.3) (layer "B.SilkS") (width 0.15))
    (fp_rect (start -1.24 0.7) (end 1.24 -0.7) (layer "B.CrtYd") (width 0.05) (fill none))
    (fp_rect (start -0.8 0.4) (end 0.8 -0.4) (layer "B.Fab") (width 0.15) (fill none))
    (pad "1" smd roundrect (at -0.7 0 270) (size 0.6 0.8) (layers "B.Cu" "B.Paste" "B.Mask") (roundrect_rratio 0.2)
      (net 66 "USB_VBUS") (pintype "passive"))
    (pad "2" smd roundrect (at 0.7 0 270) (size 0.6 0.8) (layers "B.Cu" "B.Paste" "B.Mask") (roundrect_rratio 0.2)
      (net 1 "GND") (pintype "passive"))
  )
	(footprint "sa800u-baseboard-hw-footprints:C_0402_1005Metric" (layer "B.Cu")
    (tedit 616D63CF)
    (at 110.55 137.5 180)
    (descr "Capacitor SMD 0402")
    (tags "capacitor SMD 0402")
    (property "Author" "Antmicro")
    (property "Dielectric" "X5R")
    (property "License" "Apache-2.0")
    (property "MPN" "GRM155R61H104KE14D")
    (property "Manufacturer" "Murata")
    (property "Sheetfile" "usb-c-interface.kicad_sch")
    (property "Sheetname" "USB-C Interface ")
    (property "Val" "100n")
    (property "Voltage" "50V")
    (attr smd)
    (fp_text reference "C63" (at -1.39 1.55) (layer "B.SilkS")
      (effects (font (size 0.7 0.7) (thickness 0.15)) (justify left bottom mirror))
    )
    (fp_text value "C_100n_0402" (at 0 -1.4) (layer "B.Fab")
      (effects (font (size 0.7 0.7) (thickness 0.15)) (justify left bottom mirror))
    )
    (fp_text user "${REFERENCE}" (at -0.932 -3.168) (layer "B.Fab") hide
      (effects (font (size 0.7 0.7) (thickness 0.15)) (justify left bottom mirror))
    )
    (fp_text user "License: Apache-2.0" (at -0.932 -5.17) (layer "B.Fab") hide
      (effects (font (size 0.7 0.7) (thickness 0.15)) (justify left bottom mirror))
    )
    (fp_text user "Author: Antmicro" (at -0.932 -4.17) (layer "B.Fab") hide
      (effects (font (size 0.7 0.7) (thickness 0.15)) (justify left bottom mirror))
    )
    (fp_rect (start -0.94 0.47) (end 0.94 -0.47) (layer "B.CrtYd") (width 0.05) (fill none))
    (fp_rect (start -0.499 0.249) (end 0.499 -0.249) (layer "B.Fab") (width 0.15) (fill none))
    (pad "1" smd roundrect (at -0.484 0 180) (size 0.59 0.64) (layers "B.Cu" "B.Paste" "B.Mask") (roundrect_rratio 0.25)
      (net 134 "1V8_SYS") (pintype "passive"))
    (pad "2" smd roundrect (at 0.484 0 180) (size 0.59 0.64) (layers "B.Cu" "B.Paste" "B.Mask") (roundrect_rratio 0.25)
      (net 1 "GND") (pintype "passive"))
  )
	(footprint "sa800u-baseboard-hw-footprints:C_0402_1005Metric" (layer "B.Cu")
    (tedit 616D63CF)
    (at 110.55 138.7 180)
    (descr "Capacitor SMD 0402")
    (tags "capacitor SMD 0402")
    (property "Author" "Antmicro")
    (property "Dielectric" "X5R")
    (property "License" "Apache-2.0")
    (property "MPN" "GRM155R61H104KE14D")
    (property "Manufacturer" "Murata")
    (property "Sheetfile" "usb-c-interface.kicad_sch")
    (property "Sheetname" "USB-C Interface ")
    (property "Val" "100n")
    (property "Voltage" "50V")
    (attr smd)
    (fp_text reference "C65" (at -1.41 1.81) (layer "B.SilkS")
      (effects (font (size 0.7 0.7) (thickness 0.15)) (justify left bottom mirror))
    )
    (fp_text value "C_100n_0402" (at 0 -1.4) (layer "B.Fab")
      (effects (font (size 0.7 0.7) (thickness 0.15)) (justify left bottom mirror))
    )
    (fp_text user "Author: Antmicro" (at -0.932 -4.17) (layer "B.Fab") hide
      (effects (font (size 0.7 0.7) (thickness 0.15)) (justify left bottom mirror))
    )
    (fp_text user "${REFERENCE}" (at -0.932 -3.168) (layer "B.Fab") hide
      (effects (font (size 0.7 0.7) (thickness 0.15)) (justify left bottom mirror))
    )
    (fp_text user "License: Apache-2.0" (at -0.932 -5.17) (layer "B.Fab") hide
      (effects (font (size 0.7 0.7) (thickness 0.15)) (justify left bottom mirror))
    )
    (fp_rect (start -0.94 0.47) (end 0.94 -0.47) (layer "B.CrtYd") (width 0.05) (fill none))
    (fp_rect (start -0.499 0.249) (end 0.499 -0.249) (layer "B.Fab") (width 0.15) (fill none))
    (pad "1" smd roundrect (at -0.484 0 180) (size 0.59 0.64) (layers "B.Cu" "B.Paste" "B.Mask") (roundrect_rratio 0.25)
      (net 133 "5V_SYS") (pintype "passive"))
    (pad "2" smd roundrect (at 0.484 0 180) (size 0.59 0.64) (layers "B.Cu" "B.Paste" "B.Mask") (roundrect_rratio 0.25)
      (net 1 "GND") (pintype "passive"))
  )
	(footprint "sa800u-baseboard-hw-footprints:R_0402_1005Metric" (layer "B.Cu")
    (tedit 5FD9C158)
    (at 110 140.9 90)
    (descr "Resistor SMD 0402")
    (tags "resistor SMD 0402")
    (property "Author" "Antmicro")
    (property "License" "Apache-2.0")
    (property "MPN" "CR0402-FX-1003GLF")
    (property "Manufacturer" "Bourns")
    (property "Sheetfile" "usb-c-interface.kicad_sch")
    (property "Sheetname" "USB-C Interface ")
    (property "Tolerance" "1%")
    (property "Val" "100k")
    (attr smd)
    (fp_text reference "R63" (at 1.06 3.34 270) (layer "B.SilkS")
      (effects (font (size 0.7 0.7) (thickness 0.15)) (justify left bottom mirror))
    )
    (fp_text value "R_100k_0402" (at 0 -1.4 270) (layer "B.Fab")
      (effects (font (size 0.7 0.7) (thickness 0.15)) (justify left bottom mirror))
    )
    (fp_text user "Author: Antmicro" (at -0.95 -4.169 270) (layer "B.Fab") hide
      (effects (font (size 0.7 0.7) (thickness 0.15)) (justify left bottom mirror))
    )
    (fp_text user "License: Apache-2.0" (at -0.95 -5.169 270) (layer "B.Fab") hide
      (effects (font (size 0.7 0.7) (thickness 0.15)) (justify left bottom mirror))
    )
    (fp_text user "${REFERENCE}" (at -0.95 -3.168 270) (layer "B.Fab") hide
      (effects (font (size 0.7 0.7) (thickness 0.15)) (justify left bottom mirror))
    )
    (fp_rect (start -0.93 0.47) (end 0.93 -0.47) (layer "B.CrtYd") (width 0.05) (fill none))
    (fp_rect (start -0.5 0.25) (end 0.5 -0.25) (layer "B.Fab") (width 0.15) (fill none))
    (pad "1" smd roundrect (at -0.485 0 90) (size 0.59 0.64) (layers "B.Cu" "B.Paste" "B.Mask") (roundrect_rratio 0.25)
      (net 292 "/USB-C Interface /USB2_FAULT_5V") (pintype "passive"))
    (pad "2" smd roundrect (at 0.485 0 90) (size 0.59 0.64) (layers "B.Cu" "B.Paste" "B.Mask") (roundrect_rratio 0.25)
      (net 133 "5V_SYS") (pintype "passive"))
  )
)
